(kicad_pcb
	(version 20260206)
	(generator "pcbnew")
	(generator_version "10.0")
	(general
		(thickness 1.6)
		(legacy_teardrops no)
	)
	(paper "A4")
	(title_block
		(title "12092022_DA0F0TMDCD0_F0T_Management_Board_D_brd_V3_OCP.brd")
		(comment 1 "Grand Teton / footprints 1064-1069 of 1440")
	)
	(layers
		(0 "F.Cu" signal "TOP")
		(4 "In1.Cu" signal "GND")
		(6 "In2.Cu" signal "IN1")
		(8 "In3.Cu" signal "GND1")
		(10 "In4.Cu" signal "IN2")
		(12 "In5.Cu" signal "VCC")
		(14 "In6.Cu" signal "VCC1")
		(16 "In7.Cu" signal "IN3")
		(18 "In8.Cu" signal "GND2")
		(20 "In9.Cu" signal "IN4")
		(22 "In10.Cu" signal "GND3")
		(2 "B.Cu" signal "BOTTOM")
		(9 "F.Adhes" user "F.Adhesive")
		(11 "B.Adhes" user "B.Adhesive")
		(13 "F.Paste" user "Package Geometry/Pastemask Top")
		(15 "B.Paste" user "Package Geometry/Pastemask Bottom")
		(5 "F.SilkS" user "Ref Des/Silkscreen Top")
		(7 "B.SilkS" user "Ref Des/Silkscreen Bottom")
		(1 "F.Mask" user "Board Geometry/Soldermask Top")
		(3 "B.Mask" user "Board Geometry/Soldermask Bottom")
		(17 "Dwgs.User" user "User.Drawings")
		(19 "Cmts.User" user "User.Comments")
		(21 "Eco1.User" user "User.Eco1")
		(23 "Eco2.User" user "User.Eco2")
		(25 "Edge.Cuts" user "Board Geometry/Outline")
		(27 "Margin" user)
		(31 "F.CrtYd" user "Package Geometry/Place Bound Top")
		(29 "B.CrtYd" user "Package Geometry/Place Bound Bottom")
		(35 "F.Fab" user "Ref Des/Assembly Top")
		(33 "B.Fab" user "Ref Des/Assembly Bottom")
	)
	(footprint ""
		(layer "B.Cu")
		(at 18.259298 -95.587058 180)
		(property "Reference" "C281"
			(at 0 0 0)
			(layer "B.SilkS")
			(hide yes)
			(effects
				(font
					(size 1.27 1.27)
				)
				(justify mirror)
			)
		)
		(property "Value" ""
			(at 0 0 0)
			(layer "B.Fab")
			(effects
				(font
					(size 1.27 1.27)
				)
				(justify mirror)
			)
		)
		(duplicate_pad_numbers_are_jumpers no)
		(fp_line
			(start 0.69215 0.2921)
			(end 0.69215 -0.2921)
			(stroke
				(width 0.1524)
				(type default)
			)
			(layer "B.SilkS")
		)
		(fp_line
			(start 0.69215 -0.2921)
			(end -0.69215 -0.2921)
			(stroke
				(width 0.1524)
				(type default)
			)
			(layer "B.SilkS")
		)
		(fp_line
			(start -0.69215 0.2921)
			(end 0.69215 0.2921)
			(stroke
				(width 0.1524)
				(type default)
			)
			(layer "B.SilkS")
		)
		(fp_line
			(start -0.69215 -0.2921)
			(end -0.69215 0.2921)
			(stroke
				(width 0.1524)
				(type default)
			)
			(layer "B.SilkS")
		)
		(fp_line
			(start 0.51435 0.2794)
			(end 0.51435 -0.2794)
			(stroke
				(width 0.1)
				(type default)
			)
			(layer "B.Fab")
		)
		(fp_line
			(start 0.51435 -0.2794)
			(end -0.51435 -0.2794)
			(stroke
				(width 0.1)
				(type default)
			)
			(layer "B.Fab")
		)
		(fp_line
			(start -0.51435 0.2794)
			(end 0.51435 0.2794)
			(stroke
				(width 0.1)
				(type default)
			)
			(layer "B.Fab")
		)
		(fp_line
			(start -0.51435 -0.2794)
			(end -0.51435 0.2794)
			(stroke
				(width 0.1)
				(type default)
			)
			(layer "B.Fab")
		)
		(pad "1" smd circle
			(at 0.40005 0)
			(size 0 0)
			(layers "B.Cu" "B.Mask" "B.Paste")
			(net "VCCIO1")
		)
		(pad "2" smd circle
			(at -0.40005 0)
			(size 0 0)
			(layers "B.Cu" "B.Mask" "B.Paste")
			(net "GND")
		)
		(zone
			(layer "B.Cu")
			(hatch none 0.5)
			(connect_pads
				(clearance 0)
			)
			(min_thickness 0.25)
			(keepout
				(tracks not_allowed)
				(vias allowed)
				(pads allowed)
				(copperpour not_allowed)
				(footprints allowed)
			)
			(placement
				(enabled no)
				(sheetname "")
			)
			(fill
				(thermal_gap 0.5)
				(thermal_bridge_width 0.5)
				(island_removal_mode 0)
			)
			(polygon
				(pts
					(xy 18.068798 -95.674688) (xy 18.160238 -95.732854) (xy 18.359628 -95.732854) (xy 18.449798 -95.674688)
					(xy 18.449798 -95.499428) (xy 18.359628 -95.441008) (xy 18.160238 -95.441008) (xy 18.068798 -95.499174)
				)
			)
		)
	)
	(footprint ""
		(layer "B.Cu")
		(at 51.2445 -92.2655 180)
		(property "Reference" "R83"
			(at 0 0 0)
			(layer "B.SilkS")
			(hide yes)
			(effects
				(font
					(size 1.27 1.27)
				)
				(justify mirror)
			)
		)
		(property "Value" ""
			(at 0 0 0)
			(layer "B.Fab")
			(effects
				(font
					(size 1.27 1.27)
				)
				(justify mirror)
			)
		)
		(duplicate_pad_numbers_are_jumpers no)
		(fp_line
			(start 0.7874 0.4064)
			(end 0.7874 -0.4064)
			(stroke
				(width 0.1524)
				(type default)
			)
			(layer "B.SilkS")
		)
		(fp_line
			(start 0.7874 -0.4064)
			(end -0.7874 -0.4064)
			(stroke
				(width 0.1524)
				(type default)
			)
			(layer "B.SilkS")
		)
		(fp_line
			(start -0.7874 0.4064)
			(end 0.7874 0.4064)
			(stroke
				(width 0.1524)
				(type default)
			)
			(layer "B.SilkS")
		)
		(fp_line
			(start -0.7874 -0.4064)
			(end -0.7874 0.4064)
			(stroke
				(width 0.1524)
				(type default)
			)
			(layer "B.SilkS")
		)
		(fp_line
			(start 0.67945 0.3048)
			(end 0.67945 -0.305054)
			(stroke
				(width 0.1)
				(type default)
			)
			(layer "B.Fab")
		)
		(fp_line
			(start 0.67945 -0.305054)
			(end 0.12065 -0.305054)
			(stroke
				(width 0.1)
				(type default)
			)
			(layer "B.Fab")
		)
		(fp_line
			(start 0.12065 0.3048)
			(end 0.67945 0.3048)
			(stroke
				(width 0.1)
				(type default)
			)
			(layer "B.Fab")
		)
		(fp_line
			(start 0.12065 0.2794)
			(end 0.12065 0.3048)
			(stroke
				(width 0.1)
				(type default)
			)
			(layer "B.Fab")
		)
		(fp_line
			(start 0.12065 -0.2794)
			(end -0.12065 -0.2794)
			(stroke
				(width 0.1)
				(type default)
			)
			(layer "B.Fab")
		)
		(fp_line
			(start 0.12065 -0.305054)
			(end 0.12065 -0.2794)
			(stroke
				(width 0.1)
				(type default)
			)
			(layer "B.Fab")
		)
		(fp_line
			(start -0.120396 0.3048)
			(end -0.120396 0.2794)
			(stroke
				(width 0.1)
				(type default)
			)
			(layer "B.Fab")
		)
		(fp_line
			(start -0.120396 0.2794)
			(end 0.12065 0.2794)
			(stroke
				(width 0.1)
				(type default)
			)
			(layer "B.Fab")
		)
		(fp_line
			(start -0.12065 -0.2794)
			(end -0.12065 -0.3048)
			(stroke
				(width 0.1)
				(type default)
			)
			(layer "B.Fab")
		)
		(fp_line
			(start -0.12065 -0.3048)
			(end -0.67945 -0.3048)
			(stroke
				(width 0.1)
				(type default)
			)
			(layer "B.Fab")
		)
		(fp_line
			(start -0.67945 0.3048)
			(end -0.120396 0.3048)
			(stroke
				(width 0.1)
				(type default)
			)
			(layer "B.Fab")
		)
		(fp_line
			(start -0.67945 -0.3048)
			(end -0.67945 0.3048)
			(stroke
				(width 0.1)
				(type default)
			)
			(layer "B.Fab")
		)
		(pad "1" smd circle
			(at 0.40005 0)
			(size 0 0)
			(layers "B.Cu" "B.Mask" "B.Paste")
			(net "FM_UART_SEL_N")
		)
		(pad "2" smd circle
			(at -0.40005 0)
			(size 0 0)
			(layers "B.Cu" "B.Mask" "B.Paste")
			(net "FM_UART_SWITCH_N")
		)
	)
	(footprint ""
		(layer "B.Cu")
		(at 46.0756 -92.5322 -90)
		(property "Reference" "C237"
			(at 0 0 90)
			(layer "B.SilkS")
			(hide yes)
			(effects
				(font
					(size 1.27 1.27)
				)
				(justify mirror)
			)
		)
		(property "Value" ""
			(at 0 0 90)
			(layer "B.Fab")
			(effects
				(font
					(size 1.27 1.27)
				)
				(justify mirror)
			)
		)
		(duplicate_pad_numbers_are_jumpers no)
		(fp_line
			(start -0.7874 0.4064)
			(end 0.7874 0.4064)
			(stroke
				(width 0.1524)
				(type default)
			)
			(layer "B.SilkS")
		)
		(fp_line
			(start 0.7874 0.4064)
			(end 0.7874 -0.4064)
			(stroke
				(width 0.1524)
				(type default)
			)
			(layer "B.SilkS")
		)
		(fp_line
			(start -0.7874 -0.4064)
			(end -0.7874 0.4064)
			(stroke
				(width 0.1524)
				(type default)
			)
			(layer "B.SilkS")
		)
		(fp_line
			(start 0.7874 -0.4064)
			(end -0.7874 -0.4064)
			(stroke
				(width 0.1524)
				(type default)
			)
			(layer "B.SilkS")
		)
		(fp_line
			(start -0.67945 0.3048)
			(end -0.120396 0.3048)
			(stroke
				(width 0.1)
				(type default)
			)
			(layer "B.Fab")
		)
		(fp_line
			(start -0.120396 0.3048)
			(end -0.120396 0.2794)
			(stroke
				(width 0.1)
				(type default)
			)
			(layer "B.Fab")
		)
		(fp_line
			(start 0.12065 0.3048)
			(end 0.67945 0.3048)
			(stroke
				(width 0.1)
				(type default)
			)
			(layer "B.Fab")
		)
		(fp_line
			(start 0.67945 0.3048)
			(end 0.67945 -0.305054)
			(stroke
				(width 0.1)
				(type default)
			)
			(layer "B.Fab")
		)
		(fp_line
			(start -0.120396 0.2794)
			(end 0.12065 0.2794)
			(stroke
				(width 0.1)
				(type default)
			)
			(layer "B.Fab")
		)
		(fp_line
			(start 0.12065 0.2794)
			(end 0.12065 0.3048)
			(stroke
				(width 0.1)
				(type default)
			)
			(layer "B.Fab")
		)
		(fp_line
			(start -0.12065 -0.2794)
			(end -0.12065 -0.3048)
			(stroke
				(width 0.1)
				(type default)
			)
			(layer "B.Fab")
		)
		(fp_line
			(start 0.12065 -0.2794)
			(end -0.12065 -0.2794)
			(stroke
				(width 0.1)
				(type default)
			)
			(layer "B.Fab")
		)
		(fp_line
			(start -0.67945 -0.3048)
			(end -0.67945 0.3048)
			(stroke
				(width 0.1)
				(type default)
			)
			(layer "B.Fab")
		)
		(fp_line
			(start -0.12065 -0.3048)
			(end -0.67945 -0.3048)
			(stroke
				(width 0.1)
				(type default)
			)
			(layer "B.Fab")
		)
		(fp_line
			(start 0.12065 -0.305054)
			(end 0.12065 -0.2794)
			(stroke
				(width 0.1)
				(type default)
			)
			(layer "B.Fab")
		)
		(fp_line
			(start 0.67945 -0.305054)
			(end 0.12065 -0.305054)
			(stroke
				(width 0.1)
				(type default)
			)
			(layer "B.Fab")
		)
		(pad "1" smd circle
			(at 0.40005 0 90)
			(size 0 0)
			(layers "B.Cu" "B.Mask" "B.Paste")
			(net "P3V3_AUX")
		)
		(pad "2" smd circle
			(at -0.40005 0 90)
			(size 0 0)
			(layers "B.Cu" "B.Mask" "B.Paste")
			(net "GND")
		)
	)
	(footprint ""
		(layer "B.Cu")
		(at 84.08924 -51.381152 180)
		(property "Reference" "C170"
			(at 0 0 0)
			(layer "B.SilkS")
			(hide yes)
			(effects
				(font
					(size 1.27 1.27)
				)
				(justify mirror)
			)
		)
		(property "Value" ""
			(at 0 0 0)
			(layer "B.Fab")
			(effects
				(font
					(size 1.27 1.27)
				)
				(justify mirror)
			)
		)
		(duplicate_pad_numbers_are_jumpers no)
		(fp_line
			(start 0.7874 0.4064)
			(end 0.7874 -0.4064)
			(stroke
				(width 0.1524)
				(type default)
			)
			(layer "B.SilkS")
		)
		(fp_line
			(start 0.7874 -0.4064)
			(end -0.7874 -0.4064)
			(stroke
				(width 0.1524)
				(type default)
			)
			(layer "B.SilkS")
		)
		(fp_line
			(start -0.7874 0.4064)
			(end 0.7874 0.4064)
			(stroke
				(width 0.1524)
				(type default)
			)
			(layer "B.SilkS")
		)
		(fp_line
			(start -0.7874 -0.4064)
			(end -0.7874 0.4064)
			(stroke
				(width 0.1524)
				(type default)
			)
			(layer "B.SilkS")
		)
		(fp_line
			(start 0.67945 0.3048)
			(end 0.67945 -0.305054)
			(stroke
				(width 0.1)
				(type default)
			)
			(layer "B.Fab")
		)
		(fp_line
			(start 0.67945 -0.305054)
			(end 0.12065 -0.305054)
			(stroke
				(width 0.1)
				(type default)
			)
			(layer "B.Fab")
		)
		(fp_line
			(start 0.12065 0.3048)
			(end 0.67945 0.3048)
			(stroke
				(width 0.1)
				(type default)
			)
			(layer "B.Fab")
		)
		(fp_line
			(start 0.12065 0.2794)
			(end 0.12065 0.3048)
			(stroke
				(width 0.1)
				(type default)
			)
			(layer "B.Fab")
		)
		(fp_line
			(start 0.12065 -0.2794)
			(end -0.12065 -0.2794)
			(stroke
				(width 0.1)
				(type default)
			)
			(layer "B.Fab")
		)
		(fp_line
			(start 0.12065 -0.305054)
			(end 0.12065 -0.2794)
			(stroke
				(width 0.1)
				(type default)
			)
			(layer "B.Fab")
		)
		(fp_line
			(start -0.120396 0.3048)
			(end -0.120396 0.2794)
			(stroke
				(width 0.1)
				(type default)
			)
			(layer "B.Fab")
		)
		(fp_line
			(start -0.120396 0.2794)
			(end 0.12065 0.2794)
			(stroke
				(width 0.1)
				(type default)
			)
			(layer "B.Fab")
		)
		(fp_line
			(start -0.12065 -0.2794)
			(end -0.12065 -0.3048)
			(stroke
				(width 0.1)
				(type default)
			)
			(layer "B.Fab")
		)
		(fp_line
			(start -0.12065 -0.3048)
			(end -0.67945 -0.3048)
			(stroke
				(width 0.1)
				(type default)
			)
			(layer "B.Fab")
		)
		(fp_line
			(start -0.67945 0.3048)
			(end -0.120396 0.3048)
			(stroke
				(width 0.1)
				(type default)
			)
			(layer "B.Fab")
		)
		(fp_line
			(start -0.67945 -0.3048)
			(end -0.67945 0.3048)
			(stroke
				(width 0.1)
				(type default)
			)
			(layer "B.Fab")
		)
		(pad "1" smd circle
			(at 0.40005 0)
			(size 0 0)
			(layers "B.Cu" "B.Mask" "B.Paste")
			(net "P0V6_DDR_VREF_AUX")
		)
		(pad "2" smd circle
			(at -0.40005 0)
			(size 0 0)
			(layers "B.Cu" "B.Mask" "B.Paste")
			(net "GND")
		)
	)
	(footprint ""
		(layer "B.Cu")
		(at 72.909176 -42.113708)
		(property "Reference" "R4"
			(at 0 0 0)
			(layer "B.SilkS")
			(hide yes)
			(effects
				(font
					(size 1.27 1.27)
				)
				(justify mirror)
			)
		)
		(property "Value" ""
			(at 0 0 0)
			(layer "B.Fab")
			(effects
				(font
					(size 1.27 1.27)
				)
				(justify mirror)
			)
		)
		(duplicate_pad_numbers_are_jumpers no)
		(fp_line
			(start -0.7874 -0.4064)
			(end -0.7874 0.4064)
			(stroke
				(width 0.1524)
				(type default)
			)
			(layer "B.SilkS")
		)
		(fp_line
			(start -0.7874 0.4064)
			(end 0.7874 0.4064)
			(stroke
				(width 0.1524)
				(type default)
			)
			(layer "B.SilkS")
		)
		(fp_line
			(start 0.7874 -0.4064)
			(end -0.7874 -0.4064)
			(stroke
				(width 0.1524)
				(type default)
			)
			(layer "B.SilkS")
		)
		(fp_line
			(start 0.7874 0.4064)
			(end 0.7874 -0.4064)
			(stroke
				(width 0.1524)
				(type default)
			)
			(layer "B.SilkS")
		)
		(fp_line
			(start -0.67945 -0.3048)
			(end -0.67945 0.3048)
			(stroke
				(width 0.1)
				(type default)
			)
			(layer "B.Fab")
		)
		(fp_line
			(start -0.67945 0.3048)
			(end -0.120396 0.3048)
			(stroke
				(width 0.1)
				(type default)
			)
			(layer "B.Fab")
		)
		(fp_line
			(start -0.12065 -0.3048)
			(end -0.67945 -0.3048)
			(stroke
				(width 0.1)
				(type default)
			)
			(layer "B.Fab")
		)
		(fp_line
			(start -0.12065 -0.2794)
			(end -0.12065 -0.3048)
			(stroke
				(width 0.1)
				(type default)
			)
			(layer "B.Fab")
		)
		(fp_line
			(start -0.120396 0.2794)
			(end 0.12065 0.2794)
			(stroke
				(width 0.1)
				(type default)
			)
			(layer "B.Fab")
		)
		(fp_line
			(start -0.120396 0.3048)
			(end -0.120396 0.2794)
			(stroke
				(width 0.1)
				(type default)
			)
			(layer "B.Fab")
		)
		(fp_line
			(start 0.12065 -0.305054)
			(end 0.12065 -0.2794)
			(stroke
				(width 0.1)
				(type default)
			)
			(layer "B.Fab")
		)
		(fp_line
			(start 0.12065 -0.2794)
			(end -0.12065 -0.2794)
			(stroke
				(width 0.1)
				(type default)
			)
			(layer "B.Fab")
		)
		(fp_line
			(start 0.12065 0.2794)
			(end 0.12065 0.3048)
			(stroke
				(width 0.1)
				(type default)
			)
			(layer "B.Fab")
		)
		(fp_line
			(start 0.12065 0.3048)
			(end 0.67945 0.3048)
			(stroke
				(width 0.1)
				(type default)
			)
			(layer "B.Fab")
		)
		(fp_line
			(start 0.67945 -0.305054)
			(end 0.12065 -0.305054)
			(stroke
				(width 0.1)
				(type default)
			)
			(layer "B.Fab")
		)
		(fp_line
			(start 0.67945 0.3048)
			(end 0.67945 -0.305054)
			(stroke
				(width 0.1)
				(type default)
			)
			(layer "B.Fab")
		)
		(pad "1" smd circle
			(at 0.40005 0 180)
			(size 0 0)
			(layers "B.Cu" "B.Mask" "B.Paste")
			(net "PD_M_BMC_DDR4_PAR")
		)
		(pad "2" smd circle
			(at -0.40005 0 180)
			(size 0 0)
			(layers "B.Cu" "B.Mask" "B.Paste")
			(net "GND")
		)
	)
	(footprint ""
		(layer "B.Cu")
		(at 72.003412 -58.051954 -90)
		(property "Reference" "L13"
			(at 0 0 90)
			(layer "B.SilkS")
			(hide yes)
			(effects
				(font
					(size 1.27 1.27)
				)
				(justify mirror)
			)
		)
		(property "Value" ""
			(at 0 0 90)
			(layer "B.Fab")
			(effects
				(font
					(size 1.27 1.27)
				)
				(justify mirror)
			)
		)
		(duplicate_pad_numbers_are_jumpers no)
		(fp_line
			(start -1.27 0.5842)
			(end 1.27 0.5842)
			(stroke
				(width 0.1524)
				(type default)
			)
			(layer "B.SilkS")
		)
		(fp_line
			(start -1.27 0.5842)
			(end -1.27 -0.5842)
			(stroke
				(width 0.1524)
				(type default)
			)
			(layer "B.SilkS")
		)
		(fp_line
			(start -0.127 0.5842)
			(end -0.127 -0.5842)
			(stroke
				(width 0.1524)
				(type default)
			)
			(layer "B.SilkS")
		)
		(fp_line
			(start 0.127 0.5842)
			(end 0.127 -0.5842)
			(stroke
				(width 0.1524)
				(type default)
			)
			(layer "B.SilkS")
		)
		(fp_line
			(start 1.27 0.5842)
			(end 1.27 -0.5842)
			(stroke
				(width 0.1524)
				(type default)
			)
			(layer "B.SilkS")
		)
		(fp_line
			(start 1.27 -0.5588)
			(end 1.27 -0.5842)
			(stroke
				(width 0.1524)
				(type default)
			)
			(layer "B.SilkS")
		)
		(fp_line
			(start 1.27 -0.5842)
			(end -1.27 -0.5842)
			(stroke
				(width 0.1524)
				(type default)
			)
			(layer "B.SilkS")
		)
		(fp_line
			(start -0.9144 0.508)
			(end 0.9144 0.508)
			(stroke
				(width 0.1)
				(type default)
			)
			(layer "B.Fab")
		)
		(fp_line
			(start 0.9144 0.508)
			(end 0.9144 0.406654)
			(stroke
				(width 0.1)
				(type default)
			)
			(layer "B.Fab")
		)
		(fp_line
			(start 0.9144 0.406654)
			(end 1.194308 0.406654)
			(stroke
				(width 0.1)
				(type default)
			)
			(layer "B.Fab")
		)
		(fp_line
			(start 1.194308 0.406654)
			(end 1.194308 -0.406654)
			(stroke
				(width 0.1)
				(type default)
			)
			(layer "B.Fab")
		)
		(fp_line
			(start -1.1938 0.4064)
			(end -0.9144 0.4064)
			(stroke
				(width 0.1)
				(type default)
			)
			(layer "B.Fab")
		)
		(fp_line
			(start -0.9144 0.4064)
			(end -0.9144 0.508)
			(stroke
				(width 0.1)
				(type default)
			)
			(layer "B.Fab")
		)
		(fp_line
			(start -1.1938 -0.406654)
			(end -1.1938 0.4064)
			(stroke
				(width 0.1)
				(type default)
			)
			(layer "B.Fab")
		)
		(fp_line
			(start -0.9144 -0.406654)
			(end -1.1938 -0.406654)
			(stroke
				(width 0.1)
				(type default)
			)
			(layer "B.Fab")
		)
		(fp_line
			(start 0.9144 -0.406654)
			(end 0.9144 -0.508)
			(stroke
				(width 0.1)
				(type default)
			)
			(layer "B.Fab")
		)
		(fp_line
			(start 1.194308 -0.406654)
			(end 0.9144 -0.406654)
			(stroke
				(width 0.1)
				(type default)
			)
			(layer "B.Fab")
		)
		(fp_line
			(start -0.9144 -0.508)
			(end -0.9144 -0.406654)
			(stroke
				(width 0.1)
				(type default)
			)
			(layer "B.Fab")
		)
		(fp_line
			(start 0.9144 -0.508)
			(end -0.9144 -0.508)
			(stroke
				(width 0.1)
				(type default)
			)
			(layer "B.Fab")
		)
		(pad "1" smd rect
			(at 0.7366 0 180)
			(size 0.7112 0.8128)
			(layers "B.Cu" "B.Mask" "B.Paste")
			(net "P1V0_AUX")
		)
		(pad "2" smd rect
			(at -0.7366 0 180)
			(size 0.7112 0.8128)
			(layers "B.Cu" "B.Mask" "B.Paste")
			(net "P1V0_STBY_PE_VCC10A")
		)
	)
)
